# T6G (Grand Teton) — schematic netlist excerpt (pin names and nets, part order shuffled) for the footprints in the layout excerpt that follows; sources: Cadence DE-HDL packaged netlist, KiCad conversion of 04192023_DAF0TMB3IC0_F0TG_MB_C_brd_V02_OCP.brd

J32  SCONN288_DDR506112002KQ  IO  pkg DDR288S_1-1VXC  page 102
  VIN_BULK0  = P12V_MEM_CPU1
  RFU0  = NC
  VIN_MGMT  = P3V3_AUX
  HSCL  = I3C_SPD_DDRE_CPU1_SCL
  HSDA  = I3C_SPD_DDRE_CPU1_SDA
  VSS0  = GND
  DQ0_A  = M_E_CPU1_SA_DQ<0>
  VSS1  = GND
  DQ1_A  = M_E_CPU1_SA_DQ<1>
  VSS2  = GND
  DQS0_A_T  = M_E_CPU1_SA_DQS_DP<0>
  DQS0_A_C  = M_E_CPU1_SA_DQS_DN<0>
  VSS3  = GND
  DQ4_A  = M_E_CPU1_SA_DQ<4>
  VSS4  = GND
  DQ5_A  = M_E_CPU1_SA_DQ<5>
  VSS5  = GND
  DQ8_A  = M_E_CPU1_SA_DQ<8>
  VSS6  = GND
  DQ9_A  = M_E_CPU1_SA_DQ<9>
  VSS7  = GND
  DQS1_A_T  = M_E_CPU1_SA_DQS_DP<1>
  DQS1_A_C  = M_E_CPU1_SA_DQS_DN<1>
  VSS8  = GND
  DQ12_A  = M_E_CPU1_SA_DQ<12>
  VSS9  = GND
  DQ13_A  = M_E_CPU1_SA_DQ<13>
  VSS10  = GND
  DQ16_A  = M_E_CPU1_SA_DQ<16>
  VSS11  = GND
  DQ17_A  = M_E_CPU1_SA_DQ<17>
  VSS12  = GND
  DQS2_A_T  = M_E_CPU1_SA_DQS_DP<2>
  DQS2_A_C  = M_E_CPU1_SA_DQS_DN<2>
  VSS13  = GND
  DQ20_A  = M_E_CPU1_SA_DQ<20>
  VSS14  = GND
  DQ21_A  = M_E_CPU1_SA_DQ<21>
  VSS15  = GND
  DQ24_A  = M_E_CPU1_SA_DQ<24>
  VSS16  = GND
  DQ25_A  = M_E_CPU1_SA_DQ<25>
  VSS17  = GND
  DQS3_A_T  = M_E_CPU1_SA_DQS_DP<3>
  DQS3_A_C  = M_E_CPU1_SA_DQS_DN<3>
  VSS18  = GND
  DQ28_A  = M_E_CPU1_SA_DQ<28>
  VSS19  = GND
  DQ29_A  = M_E_CPU1_SA_DQ<29>
  VSS20  = GND
  CB0_A  = M_E_CPU1_SA_CB<0>
  VSS21  = GND
  CB1_A  = M_E_CPU1_SA_CB<1>
  VSS22  = GND
  DQS4_A_T  = M_E_CPU1_SA_DQS_DP<4>
  DQS4_A_C  = M_E_CPU1_SA_DQS_DN<4>
  VSS23  = GND
  CB4_A  = M_E_CPU1_SA_CB<4>
  VSS24  = GND
  CB5_A  = M_E_CPU1_SA_CB<5>
  VSS25  = GND
  ALERT_N  = M_E_CPU1_ALERT_N
  VSS26  = GND
  CS0_A_N  = M_E_CPU1_SA_CS_N<0>
  VSS27  = GND
  CA0_A  = M_E_CPU1_SA_CA<0>
  VSS28  = GND
  CA2_A  = M_E_CPU1_SA_CA<2>
  VSS29  = GND
  CA4_A  = M_E_CPU1_SA_CA<4>
  VSS30  = GND
  CA6_A  = M_E_CPU1_SA_CA<6>
  VSS31  = GND
  PAR_A  = M_E_CPU1_SA_PAR
  VSS32  = GND
  CA0_B  = M_E_CPU1_SB_CA<0>
  VSS33  = GND
  CA2_B  = M_E_CPU1_SB_CA<2>
  VSS34  = GND
  CA4_B  = M_E_CPU1_SB_CA<4>
  VSS35  = GND
  CA6_B  = M_E_CPU1_SB_CA<6>
  VSS36  = GND
  CS0_B_N  = M_E_CPU1_SB_CS_N<0>
  VSS37  = GND
  \lbd||rsp_a_n\  = M_E_CPU1_SA_RSP<0>
  \lbs||rsp_b_n\  = M_E_CPU1_SB_RSP<0>
  VSS38  = GND
  CB4_B  = M_E_CPU1_SB_CB<4>
  VSS39  = GND
  CB5_B  = M_E_CPU1_SB_CB<5>
  VSS40  = GND
  \dqs9_b_t||tdqs9_b_t||dbi4_b_n\  = M_E_CPU1_SB_DQS_DP<9>
  \dqs9_b_c||tdqs9_b_c\  = M_E_CPU1_SB_DQS_DN<9>
  VSS41  = GND
  CB0_B  = M_E_CPU1_SB_CB<0>
  VSS42  = GND
  CB1_B  = M_E_CPU1_SB_CB<1>
  VSS43  = GND
  DQ0_B  = M_E_CPU1_SB_DQ<0>
  VSS44  = GND
  DQ1_B  = M_E_CPU1_SB_DQ<1>
  VSS45  = GND
  DQS0_B_T  = M_E_CPU1_SB_DQS_DP<0>
  DQS0_B_C  = M_E_CPU1_SB_DQS_DN<0>
  VSS46  = GND
  DQ4_B  = M_E_CPU1_SB_DQ<4>
  VSS47  = GND
  DQ5_B  = M_E_CPU1_SB_DQ<5>
  VSS48  = GND
  DQ8_B  = M_E_CPU1_SB_DQ<8>
  VSS49  = GND
  DQ9_B  = M_E_CPU1_SB_DQ<9>
  VSS50  = GND
  DQS1_B_T  = M_E_CPU1_SB_DQS_DP<1>
  DQS1_B_C  = M_E_CPU1_SB_DQS_DN<1>
  VSS51  = GND
  DQ12_B  = M_E_CPU1_SB_DQ<12>
  VSS52  = GND
  DQ13_B  = M_E_CPU1_SB_DQ<13>
  VSS53  = GND
  DQ16_B  = M_E_CPU1_SB_DQ<16>
  VSS54  = GND
  DQ17_B  = M_E_CPU1_SB_DQ<17>
  VSS55  = GND
  DQS2_B_T  = M_E_CPU1_SB_DQS_DP<2>
  DQS2_B_C  = M_E_CPU1_SB_DQS_DN<2>
  VSS56  = GND
  DQ20_B  = M_E_CPU1_SB_DQ<20>
  VSS57  = GND
  DQ21_B  = M_E_CPU1_SB_DQ<21>
  VSS58  = GND
  DQ24_B  = M_E_CPU1_SB_DQ<24>
  VSS59  = GND
  DQ25_B  = M_E_CPU1_SB_DQ<25>
  VSS60  = GND
  DQS3_B_T  = M_E_CPU1_SB_DQS_DP<3>
  DQS3_B_C  = M_E_CPU1_SB_DQS_DN<3>
  VSS61  = GND
  DQ28_B  = M_E_CPU1_SB_DQ<28>
  VSS62  = GND
  DQ29_B  = M_E_CPU1_SB_DQ<29>
  VSS63  = GND
  RFU1  = NC
  VIN_BULK1  = P12V_MEM_CPU1
  VIN_BULK2  = P12V_MEM_CPU1
  \pwr_good||fail_n\  = PWRGD_CHE_CPU1_DIMM
  HAS  = PD_CHE_CPU1_DIMM_SAA
  RFU2  = NC
  RFU3  = NC
  VSS64  = GND
  DQ2_A  = M_E_CPU1_SA_DQ<2>
  VSS65  = GND
  DQ3_A  = M_E_CPU1_SA_DQ<3>
  VSS66  = GND
  \dqs5_a_c||tdqs5_a_c||dqs5_a_t||tdqs5_a_t\  = M_E_CPU1_SA_DQS_DN<5>
  \dqs5_a_t||tdqs5_a_t\  = M_E_CPU1_SA_DQS_DP<5>
  VSS67  = GND
  DQ6_A  = M_E_CPU1_SA_DQ<6>
  VSS68  = GND
  DQ7_A  = M_E_CPU1_SA_DQ<7>
  VSS69  = GND
  DQ10_A  = M_E_CPU1_SA_DQ<10>
  VSS70  = GND
  DQ11_A  = M_E_CPU1_SA_DQ<11>
  VSS71  = GND
  \dqs6_a_c||tdqs6_a_c||dqs6_a_t||tdqs6_a_t\  = M_E_CPU1_SA_DQS_DN<6>
  \dqs6_a_t||tdqs6_a_t\  = M_E_CPU1_SA_DQS_DP<6>
  VSS72  = GND
  DQ14_A  = M_E_CPU1_SA_DQ<14>
  VSS73  = GND
  DQ15_A  = M_E_CPU1_SA_DQ<15>
  VSS74  = GND
  DQ18_A  = M_E_CPU1_SA_DQ<18>
  VSS75  = GND
  DQ19_A  = M_E_CPU1_SA_DQ<19>
  VSS76  = GND
  \dqs7_a_c||tdqs7_a_c\  = M_E_CPU1_SA_DQS_DN<7>
  \dqs7_a_t||tdqs7_a_t\  = M_E_CPU1_SA_DQS_DP<7>
  VSS77  = GND
  DQ22_A  = M_E_CPU1_SA_DQ<22>
  VSS78  = GND
  DQ23_A  = M_E_CPU1_SA_DQ<23>
  VSS79  = GND
  DQ26_A  = M_E_CPU1_SA_DQ<26>
  VSS80  = GND
  DQ27_A  = M_E_CPU1_SA_DQ<27>
  VSS81  = GND
  \dqs8_a_c||tdqs8_a_c\  = M_E_CPU1_SA_DQS_DN<8>
  \dqs8_a_t||tdqs8_a_t\  = M_E_CPU1_SA_DQS_DP<8>
  VSS82  = GND
  DQ30_A  = M_E_CPU1_SA_DQ<30>
  VSS83  = GND
  DQ31_A  = M_E_CPU1_SA_DQ<31>
  VSS84  = GND
  CB2_A  = M_E_CPU1_SA_CB<2>
  VSS85  = GND
  CB3_A  = M_E_CPU1_SA_CB<3>
  VSS86  = GND
  \dqs9_a_c||tdqs9_a_c\  = M_E_CPU1_SA_DQS_DN<9>
  \dqs9_a_t||tdqs9_a_t\  = M_E_CPU1_SA_DQS_DP<9>
  VSS87  = GND
  CB6_A  = M_E_CPU1_SA_CB<6>
  VSS88  = GND
  CB7_A  = M_E_CPU1_SA_CB<7>
  VSS89  = GND
  RESET_N  = M_E_CPU1_RESET_N
  VSS90  = GND
  CS1_A_N  = M_E_CPU1_SA_CS_N<1>
  VSS91  = GND
  CA1_A  = M_E_CPU1_SA_CA<1>
  VSS92  = GND
  CA3_A  = M_E_CPU1_SA_CA<3>
  VSS93  = GND
  CA5_A  = M_E_CPU1_SA_CA<5>
  VSS94  = GND
  CK_T  = M_E_CPU1_CLK_DP<0>
  CK_C  = M_E_CPU1_CLK_DN<0>
  VSS95  = GND
  RFU4  = NC
  CA1_B  = M_E_CPU1_SB_CA<1>
  VSS96  = GND
  CA3_B  = M_E_CPU1_SB_CA<3>
  VSS97  = GND
  CA5_B  = M_E_CPU1_SB_CA<5>
  VSS98  = GND
  PAR_B  = M_E_CPU1_SB_PAR
  VSS99  = GND
  CS1_B_N  = M_E_CPU1_SB_CS_N<1>
  VSS100  = GND
  RFU5  = NC
  RFU6  = NC
  VSS101  = GND
  CB6_B  = M_E_CPU1_SB_CB<6>
  VSS102  = GND
  CB7_B  = M_E_CPU1_SB_CB<7>
  VSS103  = GND
  DQS4_B_C  = M_E_CPU1_SB_DQS_DN<4>
  DQS4_B_T  = M_E_CPU1_SB_DQS_DP<4>
  VSS104  = GND
  CB2_B  = M_E_CPU1_SB_CB<2>
  VSS105  = GND
  CB3_B  = M_E_CPU1_SB_CB<3>
  VSS106  = GND
  DQ2_B  = M_E_CPU1_SB_DQ<2>
  VSS107  = GND
  DQ3_B  = M_E_CPU1_SB_DQ<3>
  VSS108  = GND
  \dqs5_b_c||tdqs5_b_c\  = M_E_CPU1_SB_DQS_DN<5>
  \dqs5_b_t||tdqs5_b_t\  = M_E_CPU1_SB_DQS_DP<5>
  VSS109  = GND
  DQ6_B  = M_E_CPU1_SB_DQ<6>
  VSS110  = GND
  DQ7_B  = M_E_CPU1_SB_DQ<7>
  VSS111  = GND
  DQ10_B  = M_E_CPU1_SB_DQ<10>
  VSS112  = GND
  DQ11_B  = M_E_CPU1_SB_DQ<11>
  VSS113  = GND
  \dqs6_b_c||tdqs6_b_c\  = M_E_CPU1_SB_DQS_DN<6>
  \dqs6_b_t||tdqs6_b_t\  = M_E_CPU1_SB_DQS_DP<6>
  VSS114  = GND
  DQ14_B  = M_E_CPU1_SB_DQ<14>
  VSS115  = GND
  DQ15_B  = M_E_CPU1_SB_DQ<15>
  VSS116  = GND
  DQ18_B  = M_E_CPU1_SB_DQ<18>
  VSS117  = GND
  DQ19_B  = M_E_CPU1_SB_DQ<19>
  VSS118  = GND
  \dqs7_b_c||tdqs7_b_c\  = M_E_CPU1_SB_DQS_DN<7>
  \dqs7_b_t||tdqs7_b_t\  = M_E_CPU1_SB_DQS_DP<7>
  VSS119  = GND
  DQ22_B  = M_E_CPU1_SB_DQ<22>
  VSS120  = GND
  DQ23_B  = M_E_CPU1_SB_DQ<23>
  VSS121  = GND
  DQ26_B  = M_E_CPU1_SB_DQ<26>
  VSS122  = GND
  DQ27_B  = M_E_CPU1_SB_DQ<27>
  VSS123  = GND
  \dqs8_b_c||tdqs8_b_c\  = M_E_CPU1_SB_DQS_DN<8>
  \dqs8_b_t||tdqs8_b_t\  = M_E_CPU1_SB_DQS_DP<8>
  VSS124  = GND
  DQ30_B  = M_E_CPU1_SB_DQ<30>
  VSS125  = GND
  DQ31_B  = M_E_CPU1_SB_DQ<31>
  VSS126  = GND
  G1  = GND
  G2  = GND
  G3  = GND

(kicad_pcb
	(version 20260206)
	(generator "pcbnew")
	(generator_version "10.0")
	(general
		(thickness 1.6)
		(legacy_teardrops no)
	)
	(paper "A4")
	(title_block
		(title "04192023_DAF0TMB3IC0_F0TG_MB_C_brd_V02_OCP.brd")
		(comment 1 "Grand Teton / footprint 4612 of 8354 (J32), pads 185-230 of 291")
	)
	(layers
		(0 "F.Cu" signal "TOP")
		(4 "In1.Cu" signal "GND")
		(6 "In2.Cu" signal "IN1")
		(8 "In3.Cu" signal "GND1")
		(10 "In4.Cu" signal "IN2")
		(12 "In5.Cu" signal "GND2")
		(14 "In6.Cu" signal "IN3")
		(16 "In7.Cu" signal "GND3")
		(18 "In8.Cu" signal "VCC")
		(20 "In9.Cu" signal "VCC1")
		(22 "In10.Cu" signal "GND4")
		(24 "In11.Cu" signal "IN4")
		(26 "In12.Cu" signal "GND5")
		(28 "In13.Cu" signal "IN5")
		(30 "In14.Cu" signal "GND6")
		(32 "In15.Cu" signal "IN6")
		(34 "In16.Cu" signal "GND7")
		(2 "B.Cu" signal "BOTTOM")
		(9 "F.Adhes" user "F.Adhesive")
		(11 "B.Adhes" user "B.Adhesive")
		(13 "F.Paste" user "Package Geometry/Pastemask Top")
		(15 "B.Paste" user "Package Geometry/Pastemask Bottom")
		(5 "F.SilkS" user "Ref Des/Silkscreen Top")
		(7 "B.SilkS" user "Ref Des/Silkscreen Bottom")
		(1 "F.Mask" user "Board Geometry/Soldermask Top")
		(3 "B.Mask" user "Board Geometry/Soldermask Bottom")
		(17 "Dwgs.User" user "User.Drawings")
		(19 "Cmts.User" user "User.Comments")
		(21 "Eco1.User" user "User.Eco1")
		(23 "Eco2.User" user "User.Eco2")
		(25 "Edge.Cuts" user "Board Geometry/Outline")
		(27 "Margin" user)
		(31 "F.CrtYd" user "Package Geometry/Place Bound Top")
		(29 "B.CrtYd" user "Package Geometry/Place Bound Bottom")
		(35 "F.Fab" user "Ref Des/Assembly Top")
		(33 "B.Fab" user "Ref Des/Assembly Bottom")
	)
	(footprint ""
		(layer "F.Cu")
		(at 27.20213 -255.560322 180)
		(property "Reference" "J32"
			(at 1.80086 -81.974436 0)
			(unlocked yes)
			(layer "F.SilkS")
			(effects
				(font
					(size 0.7874 0.5842)
					(thickness 0.1524)
				)
			)
		)
		(property "Value" ""
			(at 0 0 180)
			(layer "F.Fab")
			(effects
				(font
					(size 1.27 1.27)
				)
			)
		)
		(duplicate_pad_numbers_are_jumpers no)
		(pad "185" smd rect
			(at 2.050034 -29.325062 90)
			(size 0.519938 1.4986)
			(layers "F.Cu" "F.Mask" "F.Paste")
			(net "M_E_CPU1_SA_DQ<26>")
		)
		(pad "186" smd rect
			(at 2.050034 -28.474924 90)
			(size 0.519938 1.4986)
			(layers "F.Cu" "F.Mask" "F.Paste")
			(net "GND")
		)
		(pad "187" smd rect
			(at 2.050034 -27.62504 90)
			(size 0.519938 1.4986)
			(layers "F.Cu" "F.Mask" "F.Paste")
			(net "M_E_CPU1_SA_DQ<27>")
		)
		(pad "188" smd rect
			(at 2.050034 -26.774902 90)
			(size 0.519938 1.4986)
			(layers "F.Cu" "F.Mask" "F.Paste")
			(net "GND")
		)
		(pad "189" smd rect
			(at 2.050034 -25.925018 90)
			(size 0.519938 1.4986)
			(layers "F.Cu" "F.Mask" "F.Paste")
			(net "M_E_CPU1_SA_DQS_DN<8>")
		)
		(pad "190" smd rect
			(at 2.050034 -25.07488 90)
			(size 0.519938 1.4986)
			(layers "F.Cu" "F.Mask" "F.Paste")
			(net "M_E_CPU1_SA_DQS_DP<8>")
		)
		(pad "191" smd rect
			(at 2.050034 -24.224996 90)
			(size 0.519938 1.4986)
			(layers "F.Cu" "F.Mask" "F.Paste")
			(net "GND")
		)
		(pad "192" smd rect
			(at 2.050034 -23.375112 90)
			(size 0.519938 1.4986)
			(layers "F.Cu" "F.Mask" "F.Paste")
			(net "M_E_CPU1_SA_DQ<30>")
		)
		(pad "193" smd rect
			(at 2.050034 -22.524974 90)
			(size 0.519938 1.4986)
			(layers "F.Cu" "F.Mask" "F.Paste")
			(net "GND")
		)
		(pad "194" smd rect
			(at 2.050034 -21.67509 90)
			(size 0.519938 1.4986)
			(layers "F.Cu" "F.Mask" "F.Paste")
			(net "M_E_CPU1_SA_DQ<31>")
		)
		(pad "195" smd rect
			(at 2.050034 -20.824952 90)
			(size 0.519938 1.4986)
			(layers "F.Cu" "F.Mask" "F.Paste")
			(net "GND")
		)
		(pad "196" smd rect
			(at 2.050034 -19.975068 90)
			(size 0.519938 1.4986)
			(layers "F.Cu" "F.Mask" "F.Paste")
			(net "M_E_CPU1_SA_CB<2>")
		)
		(pad "197" smd rect
			(at 2.050034 -19.12493 90)
			(size 0.519938 1.4986)
			(layers "F.Cu" "F.Mask" "F.Paste")
			(net "GND")
		)
		(pad "198" smd rect
			(at 2.050034 -18.275046 90)
			(size 0.519938 1.4986)
			(layers "F.Cu" "F.Mask" "F.Paste")
			(net "M_E_CPU1_SA_CB<3>")
		)
		(pad "199" smd rect
			(at 2.050034 -17.424908 90)
			(size 0.519938 1.4986)
			(layers "F.Cu" "F.Mask" "F.Paste")
			(net "GND")
		)
		(pad "200" smd rect
			(at 2.050034 -16.575024 90)
			(size 0.519938 1.4986)
			(layers "F.Cu" "F.Mask" "F.Paste")
			(net "M_E_CPU1_SA_DQS_DN<9>")
		)
		(pad "201" smd rect
			(at 2.050034 -15.724886 90)
			(size 0.519938 1.4986)
			(layers "F.Cu" "F.Mask" "F.Paste")
			(net "M_E_CPU1_SA_DQS_DP<9>")
		)
		(pad "202" smd rect
			(at 2.050034 -14.875002 90)
			(size 0.519938 1.4986)
			(layers "F.Cu" "F.Mask" "F.Paste")
			(net "GND")
		)
		(pad "203" smd rect
			(at 2.050034 -14.025118 90)
			(size 0.519938 1.4986)
			(layers "F.Cu" "F.Mask" "F.Paste")
			(net "M_E_CPU1_SA_CB<6>")
		)
		(pad "204" smd rect
			(at 2.050034 -13.17498 90)
			(size 0.519938 1.4986)
			(layers "F.Cu" "F.Mask" "F.Paste")
			(net "GND")
		)
		(pad "205" smd rect
			(at 2.050034 -12.325096 90)
			(size 0.519938 1.4986)
			(layers "F.Cu" "F.Mask" "F.Paste")
			(net "M_E_CPU1_SA_CB<7>")
		)
		(pad "206" smd rect
			(at 2.050034 -11.474958 90)
			(size 0.519938 1.4986)
			(layers "F.Cu" "F.Mask" "F.Paste")
			(net "GND")
		)
		(pad "207" smd rect
			(at 2.050034 -10.625074 90)
			(size 0.519938 1.4986)
			(layers "F.Cu" "F.Mask" "F.Paste")
			(net "M_E_CPU1_RESET_N")
		)
		(pad "208" smd rect
			(at 2.050034 -9.774936 90)
			(size 0.519938 1.4986)
			(layers "F.Cu" "F.Mask" "F.Paste")
			(net "GND")
		)
		(pad "209" smd rect
			(at 2.050034 -8.925052 90)
			(size 0.519938 1.4986)
			(layers "F.Cu" "F.Mask" "F.Paste")
			(net "M_E_CPU1_SA_CS_N<1>")
		)
		(pad "210" smd rect
			(at 2.050034 -8.074914 90)
			(size 0.519938 1.4986)
			(layers "F.Cu" "F.Mask" "F.Paste")
			(net "GND")
		)
		(pad "211" smd rect
			(at 2.050034 -7.22503 90)
			(size 0.519938 1.4986)
			(layers "F.Cu" "F.Mask" "F.Paste")
			(net "M_E_CPU1_SA_CA<1>")
		)
		(pad "212" smd rect
			(at 2.050034 -6.374892 90)
			(size 0.519938 1.4986)
			(layers "F.Cu" "F.Mask" "F.Paste")
			(net "GND")
		)
		(pad "213" smd rect
			(at 2.050034 -5.525008 90)
			(size 0.519938 1.4986)
			(layers "F.Cu" "F.Mask" "F.Paste")
			(net "M_E_CPU1_SA_CA<3>")
		)
		(pad "214" smd rect
			(at 2.050034 -4.675124 90)
			(size 0.519938 1.4986)
			(layers "F.Cu" "F.Mask" "F.Paste")
			(net "GND")
		)
		(pad "215" smd rect
			(at 2.050034 -3.824986 90)
			(size 0.519938 1.4986)
			(layers "F.Cu" "F.Mask" "F.Paste")
			(net "M_E_CPU1_SA_CA<5>")
		)
		(pad "216" smd rect
			(at 2.050034 -2.975102 90)
			(size 0.519938 1.4986)
			(layers "F.Cu" "F.Mask" "F.Paste")
			(net "GND")
		)
		(pad "217" smd rect
			(at 2.050034 -2.124964 90)
			(size 0.519938 1.4986)
			(layers "F.Cu" "F.Mask" "F.Paste")
			(net "M_E_CPU1_CLK_DP<0>")
		)
		(pad "218" smd rect
			(at 2.050034 -1.27508 90)
			(size 0.519938 1.4986)
			(layers "F.Cu" "F.Mask" "F.Paste")
			(net "M_E_CPU1_CLK_DN<0>")
		)
		(pad "219" smd rect
			(at 2.050034 -0.424942 90)
			(size 0.519938 1.4986)
			(layers "F.Cu" "F.Mask" "F.Paste")
			(net "GND")
		)
		(pad "220" smd rect
			(at 2.050034 5.525008 90)
			(size 0.519938 1.4986)
			(layers "F.Cu" "F.Mask" "F.Paste")
			(net "Net_2316")
		)
		(pad "221" smd rect
			(at 2.050034 6.374892 90)
			(size 0.519938 1.4986)
			(layers "F.Cu" "F.Mask" "F.Paste")
			(net "M_E_CPU1_SB_CA<1>")
		)
		(pad "222" smd rect
			(at 2.050034 7.22503 90)
			(size 0.519938 1.4986)
			(layers "F.Cu" "F.Mask" "F.Paste")
			(net "GND")
		)
		(pad "223" smd rect
			(at 2.050034 8.074914 90)
			(size 0.519938 1.4986)
			(layers "F.Cu" "F.Mask" "F.Paste")
			(net "M_E_CPU1_SB_CA<3>")
		)
		(pad "224" smd rect
			(at 2.050034 8.925052 90)
			(size 0.519938 1.4986)
			(layers "F.Cu" "F.Mask" "F.Paste")
			(net "GND")
		)
		(pad "225" smd rect
			(at 2.050034 9.774936 90)
			(size 0.519938 1.4986)
			(layers "F.Cu" "F.Mask" "F.Paste")
			(net "M_E_CPU1_SB_CA<5>")
		)
		(pad "226" smd rect
			(at 2.050034 10.625074 90)
			(size 0.519938 1.4986)
			(layers "F.Cu" "F.Mask" "F.Paste")
			(net "GND")
		)
		(pad "227" smd rect
			(at 2.050034 11.474958 90)
			(size 0.519938 1.4986)
			(layers "F.Cu" "F.Mask" "F.Paste")
			(net "M_E_CPU1_SB_PAR")
		)
		(pad "228" smd rect
			(at 2.050034 12.325096 90)
			(size 0.519938 1.4986)
			(layers "F.Cu" "F.Mask" "F.Paste")
			(net "GND")
		)
		(pad "229" smd rect
			(at 2.050034 13.17498 90)
			(size 0.519938 1.4986)
			(layers "F.Cu" "F.Mask" "F.Paste")
			(net "M_E_CPU1_SB_CS_N<1>")
		)
		(pad "230" smd rect
			(at 2.050034 14.025118 90)
			(size 0.519938 1.4986)
			(layers "F.Cu" "F.Mask" "F.Paste")
			(net "GND")
		)
	)
)
